# S9S_MB_2U (Grand Teton) — schematic netlist excerpt (pin names and nets, part order shuffled) for the footprints in the layout excerpt that follows; sources: Cadence DE-HDL packaged netlist, KiCad conversion of 03242023_DA0F0TMBIJ0_F0T_Motherboard_J_brd_V01_OCP.brd

R4793  Q_RES  1M 1% EMPTY  pkg 0402LF  page 306 : A = HSC_OC_VOL ; B = HSC_D_OC_R2
PR1789  Q_RES  3.3 1% CHIP  pkg 0402LF  page 286 : A = SW_PVCCIN_CPU1_BOOT3 ; B = SW_PVCCIN_CPU1_BOOT3_R

(kicad_pcb
	(version 20260206)
	(generator "pcbnew")
	(generator_version "10.0")
	(general
		(thickness 1.6)
		(legacy_teardrops no)
	)
	(paper "A4")
	(title_block
		(title "03242023_DA0F0TMBIJ0_F0T_Motherboard_J_brd_V01_OCP.brd")
		(comment 1 "Grand Teton / footprints 637-638 of 6105")
	)
	(layers
		(0 "F.Cu" signal "TOP")
		(4 "In1.Cu" signal "GND")
		(6 "In2.Cu" signal "IN1")
		(8 "In3.Cu" signal "GND1")
		(10 "In4.Cu" signal "IN2")
		(12 "In5.Cu" signal "GND2")
		(14 "In6.Cu" signal "IN3")
		(16 "In7.Cu" signal "GND3")
		(18 "In8.Cu" signal "VCC")
		(20 "In9.Cu" signal "VCC1")
		(22 "In10.Cu" signal "GND4")
		(24 "In11.Cu" signal "IN4")
		(26 "In12.Cu" signal "GND5")
		(28 "In13.Cu" signal "IN5")
		(30 "In14.Cu" signal "GND6")
		(32 "In15.Cu" signal "IN6")
		(34 "In16.Cu" signal "GND7")
		(2 "B.Cu" signal "BOTTOM")
		(9 "F.Adhes" user "F.Adhesive")
		(11 "B.Adhes" user "B.Adhesive")
		(13 "F.Paste" user "Package Geometry/Pastemask Top")
		(15 "B.Paste" user "Package Geometry/Pastemask Bottom")
		(5 "F.SilkS" user "Ref Des/Silkscreen Top")
		(7 "B.SilkS" user "Ref Des/Silkscreen Bottom")
		(1 "F.Mask" user "Board Geometry/Soldermask Top")
		(3 "B.Mask" user "Board Geometry/Soldermask Bottom")
		(17 "Dwgs.User" user "User.Drawings")
		(19 "Cmts.User" user "User.Comments")
		(21 "Eco1.User" user "User.Eco1")
		(23 "Eco2.User" user "User.Eco2")
		(25 "Edge.Cuts" user "Board Geometry/Outline")
		(27 "Margin" user)
		(31 "F.CrtYd" user "Package Geometry/Place Bound Top")
		(29 "B.CrtYd" user "Package Geometry/Place Bound Bottom")
		(35 "F.Fab" user "Ref Des/Assembly Top")
		(33 "B.Fab" user "Ref Des/Assembly Bottom")
	)
	(footprint ""
		(layer "F.Cu")
		(at 183.85028 -411.20568 -90)
		(property "Reference" "R4793"
			(at 0 0 270)
			(layer "F.SilkS")
			(hide yes)
			(effects
				(font
					(size 1.27 1.27)
				)
			)
		)
		(property "Value" ""
			(at 0 0 270)
			(layer "F.Fab")
			(effects
				(font
					(size 1.27 1.27)
				)
			)
		)
		(duplicate_pad_numbers_are_jumpers no)
		(fp_line
			(start -0.7874 0.4064)
			(end -0.7874 -0.4064)
			(stroke
				(width 0.1524)
				(type default)
			)
			(layer "F.SilkS")
		)
		(fp_line
			(start 0.7874 0.4064)
			(end -0.7874 0.4064)
			(stroke
				(width 0.1524)
				(type default)
			)
			(layer "F.SilkS")
		)
		(fp_line
			(start -0.7874 -0.4064)
			(end 0.7874 -0.4064)
			(stroke
				(width 0.1524)
				(type default)
			)
			(layer "F.SilkS")
		)
		(fp_line
			(start 0.7874 -0.4064)
			(end 0.7874 0.4064)
			(stroke
				(width 0.1524)
				(type default)
			)
			(layer "F.SilkS")
		)
		(fp_line
			(start -0.67945 0.3048)
			(end -0.67945 -0.305054)
			(stroke
				(width 0.1)
				(type default)
			)
			(layer "F.Fab")
		)
		(fp_line
			(start -0.12065 0.3048)
			(end -0.67945 0.3048)
			(stroke
				(width 0.1)
				(type default)
			)
			(layer "F.Fab")
		)
		(fp_line
			(start 0.120396 0.3048)
			(end 0.120396 0.2794)
			(stroke
				(width 0.1)
				(type default)
			)
			(layer "F.Fab")
		)
		(fp_line
			(start 0.67945 0.3048)
			(end 0.120396 0.3048)
			(stroke
				(width 0.1)
				(type default)
			)
			(layer "F.Fab")
		)
		(fp_line
			(start -0.12065 0.2794)
			(end -0.12065 0.3048)
			(stroke
				(width 0.1)
				(type default)
			)
			(layer "F.Fab")
		)
		(fp_line
			(start 0.120396 0.2794)
			(end -0.12065 0.2794)
			(stroke
				(width 0.1)
				(type default)
			)
			(layer "F.Fab")
		)
		(fp_line
			(start -0.12065 -0.2794)
			(end 0.12065 -0.2794)
			(stroke
				(width 0.1)
				(type default)
			)
			(layer "F.Fab")
		)
		(fp_line
			(start 0.12065 -0.2794)
			(end 0.12065 -0.3048)
			(stroke
				(width 0.1)
				(type default)
			)
			(layer "F.Fab")
		)
		(fp_line
			(start 0.12065 -0.3048)
			(end 0.67945 -0.3048)
			(stroke
				(width 0.1)
				(type default)
			)
			(layer "F.Fab")
		)
		(fp_line
			(start 0.67945 -0.3048)
			(end 0.67945 0.3048)
			(stroke
				(width 0.1)
				(type default)
			)
			(layer "F.Fab")
		)
		(fp_line
			(start -0.67945 -0.305054)
			(end -0.12065 -0.305054)
			(stroke
				(width 0.1)
				(type default)
			)
			(layer "F.Fab")
		)
		(fp_line
			(start -0.12065 -0.305054)
			(end -0.12065 -0.2794)
			(stroke
				(width 0.1)
				(type default)
			)
			(layer "F.Fab")
		)
		(pad "1" smd circle
			(at -0.40005 0 270)
			(size 0 0)
			(layers "F.Cu" "F.Mask" "F.Paste")
			(net "HSC_OC_VOL")
		)
		(pad "2" smd circle
			(at 0.40005 0 270)
			(size 0 0)
			(layers "F.Cu" "F.Mask" "F.Paste")
			(net "HSC_D_OC_R2")
		)
	)
	(footprint ""
		(layer "F.Cu")
		(at 114.013742 -338.180172 90)
		(property "Reference" "PR1789"
			(at 0 0 90)
			(layer "F.SilkS")
			(hide yes)
			(effects
				(font
					(size 1.27 1.27)
				)
			)
		)
		(property "Value" ""
			(at 0 0 90)
			(layer "F.Fab")
			(effects
				(font
					(size 1.27 1.27)
				)
			)
		)
		(duplicate_pad_numbers_are_jumpers no)
		(fp_line
			(start 0.7874 -0.4064)
			(end 0.7874 0.4064)
			(stroke
				(width 0.1524)
				(type default)
			)
			(layer "F.SilkS")
		)
		(fp_line
			(start -0.7874 -0.4064)
			(end 0.7874 -0.4064)
			(stroke
				(width 0.1524)
				(type default)
			)
			(layer "F.SilkS")
		)
		(fp_line
			(start 0.7874 0.4064)
			(end -0.7874 0.4064)
			(stroke
				(width 0.1524)
				(type default)
			)
			(layer "F.SilkS")
		)
		(fp_line
			(start -0.7874 0.4064)
			(end -0.7874 -0.4064)
			(stroke
				(width 0.1524)
				(type default)
			)
			(layer "F.SilkS")
		)
		(fp_line
			(start -0.12065 -0.305054)
			(end -0.12065 -0.2794)
			(stroke
				(width 0.1)
				(type default)
			)
			(layer "F.Fab")
		)
		(fp_line
			(start -0.67945 -0.305054)
			(end -0.12065 -0.305054)
			(stroke
				(width 0.1)
				(type default)
			)
			(layer "F.Fab")
		)
		(fp_line
			(start 0.67945 -0.3048)
			(end 0.67945 0.3048)
			(stroke
				(width 0.1)
				(type default)
			)
			(layer "F.Fab")
		)
		(fp_line
			(start 0.12065 -0.3048)
			(end 0.67945 -0.3048)
			(stroke
				(width 0.1)
				(type default)
			)
			(layer "F.Fab")
		)
		(fp_line
			(start 0.12065 -0.2794)
			(end 0.12065 -0.3048)
			(stroke
				(width 0.1)
				(type default)
			)
			(layer "F.Fab")
		)
		(fp_line
			(start -0.12065 -0.2794)
			(end 0.12065 -0.2794)
			(stroke
				(width 0.1)
				(type default)
			)
			(layer "F.Fab")
		)
		(fp_line
			(start 0.120396 0.2794)
			(end -0.12065 0.2794)
			(stroke
				(width 0.1)
				(type default)
			)
			(layer "F.Fab")
		)
		(fp_line
			(start -0.12065 0.2794)
			(end -0.12065 0.3048)
			(stroke
				(width 0.1)
				(type default)
			)
			(layer "F.Fab")
		)
		(fp_line
			(start 0.67945 0.3048)
			(end 0.120396 0.3048)
			(stroke
				(width 0.1)
				(type default)
			)
			(layer "F.Fab")
		)
		(fp_line
			(start 0.120396 0.3048)
			(end 0.120396 0.2794)
			(stroke
				(width 0.1)
				(type default)
			)
			(layer "F.Fab")
		)
		(fp_line
			(start -0.12065 0.3048)
			(end -0.67945 0.3048)
			(stroke
				(width 0.1)
				(type default)
			)
			(layer "F.Fab")
		)
		(fp_line
			(start -0.67945 0.3048)
			(end -0.67945 -0.305054)
			(stroke
				(width 0.1)
				(type default)
			)
			(layer "F.Fab")
		)
		(pad "1" smd circle
			(at -0.40005 0 90)
			(size 0 0)
			(layers "F.Cu" "F.Mask" "F.Paste")
			(net "SW_PVCCIN_CPU1_BOOT3")
		)
		(pad "2" smd circle
			(at 0.40005 0 90)
			(size 0 0)
			(layers "F.Cu" "F.Mask" "F.Paste")
			(net "SW_PVCCIN_CPU1_BOOT3_R")
		)
	)
)
